# TIMECARD (Time Appliance Project (Time Card)) — schematic netlist excerpt (pin names and nets, part order shuffled) for the footprints in the layout excerpt that follows; sources: Cadence DE-HDL packaged netlist, KiCad conversion of R4006-B0001-02_R01.brd

C47  CAPACITOR  12PF 50V 5%  pkg SMC_0201R  page 20 : \1\ = UNNAMED_9_BNO080LGA28_I29_XOUT3 ; \2\ = SG
R301  RESISTOR  4.7KOHM 1%  pkg SMC_0402R_H016  page 20 : \1\ = R_BNO080_RST_N ; \2\ = SG

(kicad_pcb
	(version 20260206)
	(generator "pcbnew")
	(generator_version "10.0")
	(general
		(thickness 1.6)
		(legacy_teardrops no)
	)
	(paper "A4")
	(title_block
		(title "timecard-production-celestica-r4006 — R4006-B0001-02_R01.brd")
		(comment 1 "Time Appliance Project (Time Card) / footprints 472-473 of 1113")
	)
	(layers
		(0 "F.Cu" signal "TOP")
		(4 "In1.Cu" signal "L02_GND1")
		(6 "In2.Cu" signal "L03_SIG1")
		(8 "In3.Cu" signal "L04_GND2")
		(10 "In4.Cu" signal "L05_VCC1")
		(12 "In5.Cu" signal "L06_VCC2")
		(14 "In6.Cu" signal "L07_GND3")
		(16 "In7.Cu" signal "L08_SIG2")
		(18 "In8.Cu" signal "L09_GND4")
		(2 "B.Cu" signal "BOTTOM")
		(9 "F.Adhes" user "F.Adhesive")
		(11 "B.Adhes" user "B.Adhesive")
		(13 "F.Paste" user "Package Geometry/Pastemask Top")
		(15 "B.Paste" user "Package Geometry/Pastemask Bottom")
		(5 "F.SilkS" user "Ref Des/Silkscreen Top")
		(7 "B.SilkS" user "Ref Des/Silkscreen Bottom")
		(1 "F.Mask" user "Board Geometry/Soldermask Top")
		(3 "B.Mask" user "Board Geometry/Soldermask Bottom")
		(17 "Dwgs.User" user "User.Drawings")
		(19 "Cmts.User" user "User.Comments")
		(21 "Eco1.User" user "User.Eco1")
		(23 "Eco2.User" user "User.Eco2")
		(25 "Edge.Cuts" user "Board Geometry/Outline")
		(27 "Margin" user)
		(31 "F.CrtYd" user "Package Geometry/Place Bound Top")
		(29 "B.CrtYd" user "Package Geometry/Place Bound Bottom")
		(35 "F.Fab" user "Ref Des/Assembly Top")
		(33 "B.Fab" user "Ref Des/Assembly Bottom")
	)
	(footprint ""
		(layer "F.Cu")
		(at 92.372942 -59.3344 -90)
		(property "Reference" "C47"
			(at 2.29235 -0.337058 0)
			(unlocked yes)
			(layer "F.SilkS")
			(effects
				(font
					(size 0.635 0.4064)
					(thickness 0.1524)
				)
			)
		)
		(property "Value" "VAL*"
			(at 0.193548 2.13614 270)
			(unlocked yes)
			(layer "F.Fab")
			(hide yes)
			(effects
				(font
					(size 0.7874 0.5842)
					(thickness 0.1524)
				)
			)
		)
		(property "Tolerance" "TOL*"
			(at 0.216154 3.1496 270)
			(unlocked yes)
			(layer "Cmts.User")
			(hide yes)
			(effects
				(font
					(size 0.7874 0.5842)
					(thickness 0.1524)
				)
			)
		)
		(property "Device Type" "CAPACITOR-G104-0A120-FJ,12PF,5%"
			(at 0.184404 1.180592 270)
			(unlocked yes)
			(layer "F.Fab")
			(hide yes)
			(effects
				(font
					(size 0.7874 0.5842)
					(thickness 0.1524)
				)
			)
		)
		(property "User Part Number" "PARTNUM*"
			(at 0.216154 4.185666 270)
			(unlocked yes)
			(layer "Cmts.User")
			(hide yes)
			(effects
				(font
					(size 0.7874 0.5842)
					(thickness 0.1524)
				)
			)
		)
		(duplicate_pad_numbers_are_jumpers no)
		(fp_line
			(start -0.671322 0.4445)
			(end -0.671322 -0.4445)
			(stroke
				(width 0.1)
				(type default)
			)
			(layer "F.SilkS")
		)
		(fp_line
			(start 0.671322 0.4445)
			(end -0.671322 0.4445)
			(stroke
				(width 0.1)
				(type default)
			)
			(layer "F.SilkS")
		)
		(fp_line
			(start -0.671322 -0.4445)
			(end 0.671322 -0.4445)
			(stroke
				(width 0.1)
				(type default)
			)
			(layer "F.SilkS")
		)
		(fp_line
			(start 0.671322 -0.4445)
			(end 0.671322 0.4445)
			(stroke
				(width 0.1)
				(type default)
			)
			(layer "F.SilkS")
		)
		(fp_rect
			(start 0.671322 0.4445)
			(end -0.671322 -0.4445)
			(stroke
				(width 0)
				(type default)
			)
			(fill no)
			(layer "F.CrtYd")
		)
		(fp_line
			(start -0.31496 0.1651)
			(end 0.31496 0.1651)
			(stroke
				(width 0.1)
				(type default)
			)
			(layer "F.Fab")
		)
		(fp_line
			(start 0.31496 0.1651)
			(end 0.31496 -0.1651)
			(stroke
				(width 0.1)
				(type default)
			)
			(layer "F.Fab")
		)
		(fp_line
			(start -0.31496 -0.1651)
			(end -0.31496 0.1651)
			(stroke
				(width 0.1)
				(type default)
			)
			(layer "F.Fab")
		)
		(fp_line
			(start 0.31496 -0.1651)
			(end -0.31496 -0.1651)
			(stroke
				(width 0.1)
				(type default)
			)
			(layer "F.Fab")
		)
		(pad "1" smd rect
			(at -0.264922 0 270)
			(size 0.3048 0.381)
			(layers "F.Cu" "F.Mask" "F.Paste")
			(net "UNNAMED_9_BNO080LGA28_I29_XOUT3")
		)
		(pad "2" smd rect
			(at 0.264922 0 270)
			(size 0.3048 0.381)
			(layers "F.Cu" "F.Mask" "F.Paste")
			(net "SG")
		)
		(zone
			(layer "F.Cu")
			(hatch none 0.5)
			(connect_pads
				(clearance 0)
			)
			(min_thickness 0.25)
			(keepout
				(tracks allowed)
				(vias not_allowed)
				(pads allowed)
				(copperpour not_allowed)
				(footprints allowed)
			)
			(placement
				(enabled no)
				(sheetname "")
			)
			(fill
				(thermal_gap 0.5)
				(thermal_bridge_width 0.5)
				(island_removal_mode 0)
			)
			(polygon
				(pts
					(xy 92.182442 -59.221878) (xy 92.563442 -59.221878) (xy 92.563442 -59.446922) (xy 92.182442 -59.446922)
				)
			)
		)
	)
	(footprint ""
		(layer "F.Cu")
		(at 80.772 -59.5376 180)
		(property "Reference" "R301"
			(at 10.287 19.51863 0)
			(unlocked yes)
			(layer "F.SilkS")
			(effects
				(font
					(size 0.7874 0.5842)
					(thickness 0.1524)
				)
			)
		)
		(property "Value" "VAL*"
			(at 0.02032 2.13233 180)
			(unlocked yes)
			(layer "F.Fab")
			(hide yes)
			(effects
				(font
					(size 0.7874 0.5842)
					(thickness 0.1524)
				)
			)
		)
		(property "Tolerance" "TOL*"
			(at 0.044704 3.05435 180)
			(unlocked yes)
			(layer "Cmts.User")
			(hide yes)
			(effects
				(font
					(size 0.7874 0.5842)
					(thickness 0.1524)
				)
			)
		)
		(property "User Part Number" "PARTNUM*"
			(at 0.02032 4.024884 180)
			(unlocked yes)
			(layer "Cmts.User")
			(hide yes)
			(effects
				(font
					(size 0.7874 0.5842)
					(thickness 0.1524)
				)
			)
		)
		(property "Device Type" "RESISTOR-G155-14701-01,4.7KOHMA"
			(at 0.008382 1.210564 180)
			(unlocked yes)
			(layer "F.Fab")
			(hide yes)
			(effects
				(font
					(size 0.7874 0.5842)
					(thickness 0.1524)
				)
			)
		)
		(duplicate_pad_numbers_are_jumpers no)
		(fp_line
			(start 1.143 0.5588)
			(end 1.143 -0.5588)
			(stroke
				(width 0.1)
				(type default)
			)
			(layer "F.SilkS")
		)
		(fp_line
			(start 1.143 -0.5588)
			(end -1.143 -0.5588)
			(stroke
				(width 0.1)
				(type default)
			)
			(layer "F.SilkS")
		)
		(fp_line
			(start -1.143 0.5588)
			(end 1.143 0.5588)
			(stroke
				(width 0.1)
				(type default)
			)
			(layer "F.SilkS")
		)
		(fp_line
			(start -1.143 -0.5588)
			(end -1.143 0.5588)
			(stroke
				(width 0.1)
				(type default)
			)
			(layer "F.SilkS")
		)
		(fp_rect
			(start 1.143 0.5588)
			(end -1.143 -0.5588)
			(stroke
				(width 0)
				(type default)
			)
			(fill no)
			(layer "F.CrtYd")
		)
		(fp_line
			(start 0.508 0.3048)
			(end 0.508 -0.3048)
			(stroke
				(width 0.1)
				(type default)
			)
			(layer "F.Fab")
		)
		(fp_line
			(start 0.508 -0.3048)
			(end -0.508 -0.3048)
			(stroke
				(width 0.1)
				(type default)
			)
			(layer "F.Fab")
		)
		(fp_line
			(start -0.508 0.3048)
			(end 0.508 0.3048)
			(stroke
				(width 0.1)
				(type default)
			)
			(layer "F.Fab")
		)
		(fp_line
			(start -0.508 -0.3048)
			(end -0.508 0.3048)
			(stroke
				(width 0.1)
				(type default)
			)
			(layer "F.Fab")
		)
		(pad "1" smd rect
			(at -0.5334 0 180)
			(size 0.7112 0.6096)
			(layers "F.Cu" "F.Mask" "F.Paste")
			(net "R_BNO080_RST_N")
		)
		(pad "2" smd rect
			(at 0.5334 0 180)
			(size 0.7112 0.6096)
			(layers "F.Cu" "F.Mask" "F.Paste")
			(net "SG")
		)
		(zone
			(layer "F.Cu")
			(hatch none 0.5)
			(connect_pads
				(clearance 0)
			)
			(min_thickness 0.25)
			(keepout
				(tracks allowed)
				(vias not_allowed)
				(pads allowed)
				(copperpour not_allowed)
				(footprints allowed)
			)
			(placement
				(enabled no)
				(sheetname "")
			)
			(fill
				(thermal_gap 0.5)
				(thermal_bridge_width 0.5)
				(island_removal_mode 0)
			)
			(polygon
				(pts
					(xy 80.6958 -59.8424) (xy 80.6958 -59.2328) (xy 80.8482 -59.2328) (xy 80.8482 -59.8424)
				)
			)
		)
	)
)
